(kicad_pcb
	(version 20241229)
	(generator "pcbnew")
	(generator_version "9.0")
	(general
		(thickness 1.6296)
		(legacy_teardrops no)
	)
	(paper "A3")
	(title_block
		(title "Thunderbolt to 10GbE adapter")
		(date "2026-04-21")
		(rev "1.1.0")
		(company "Antmicro Ltd")
		(comment 1 "www.antmicro.com")
		(comment 9 "footprints 644-647 of 703")
	)
	(layers
		(0 "F.Cu" signal)
		(4 "In1.Cu" signal)
		(6 "In2.Cu" signal)
		(8 "In3.Cu" signal)
		(10 "In4.Cu" signal)
		(12 "In5.Cu" signal)
		(14 "In6.Cu" signal)
		(2 "B.Cu" signal)
		(9 "F.Adhes" user "F.Adhesive")
		(11 "B.Adhes" user "B.Adhesive")
		(13 "F.Paste" user)
		(15 "B.Paste" user)
		(5 "F.SilkS" user "F.Silkscreen")
		(7 "B.SilkS" user "B.Silkscreen")
		(1 "F.Mask" user)
		(3 "B.Mask" user)
		(17 "Dwgs.User" user "User.Drawings")
		(19 "Cmts.User" user "User.Comments")
		(21 "Eco1.User" user "User.Eco1")
		(23 "Eco2.User" user "User.Eco2")
		(25 "Edge.Cuts" user)
		(27 "Margin" user)
		(31 "F.CrtYd" user "F.Courtyard")
		(29 "B.CrtYd" user "B.Courtyard")
		(35 "F.Fab" user)
		(33 "B.Fab" user)
	)
	(footprint "antmicro-footprints:C_Pol_EIA-A"
		(layer "B.Cu")
		(at 143.2 103.7 -90)
		(property "Reference" "C330"
			(at 2.2 -0.4 90)
			(layer "B.SilkS")
			(effects
				(font
					(size 0.7 0.7)
					(thickness 0.15)
				)
				(justify left bottom mirror)
			)
		)
		(property "Value" "C_Pol_100u_6V_KEMET-T490-A"
			(at 0 -2 90)
			(layer "B.Fab")
			(effects
				(font
					(size 0.7 0.7)
					(thickness 0.15)
				)
				(justify left bottom mirror)
			)
		)
		(property "Datasheet" "https://www.kemet.com/en/us/capacitors/product/T490A107M006ATE800.html"
			(at 0 0 90)
			(layer "B.Fab")
			(hide yes)
			(effects
				(font
					(size 1.27 1.27)
					(thickness 0.15)
				)
				(justify mirror)
			)
		)
		(property "Description" "Surface Mount Tantalum Capacitor,  Solid SMD 6V 100uF 1206 20% ESR=800mOhms"
			(at 0 0 90)
			(layer "B.Fab")
			(hide yes)
			(effects
				(font
					(size 1.27 1.27)
					(thickness 0.15)
				)
				(justify mirror)
			)
		)
		(property "Val" "100u"
			(at 0 0 270)
			(unlocked yes)
			(layer "B.Fab")
			(hide yes)
			(effects
				(font
					(size 1 1)
					(thickness 0.15)
				)
				(justify mirror)
			)
		)
		(property "MPN" "T490A107M006ATE800"
			(at 0 0 270)
			(unlocked yes)
			(layer "B.Fab")
			(hide yes)
			(effects
				(font
					(size 1 1)
					(thickness 0.15)
				)
				(justify mirror)
			)
		)
		(property "Manufacturer" "KEMET"
			(at 0 0 270)
			(unlocked yes)
			(layer "B.Fab")
			(hide yes)
			(effects
				(font
					(size 1 1)
					(thickness 0.15)
				)
				(justify mirror)
			)
		)
		(property "License" "Apache-2.0"
			(at 0 0 270)
			(unlocked yes)
			(layer "B.Fab")
			(hide yes)
			(effects
				(font
					(size 1 1)
					(thickness 0.15)
				)
				(justify mirror)
			)
		)
		(property "Author" "Antmicro"
			(at 0 0 270)
			(unlocked yes)
			(layer "B.Fab")
			(hide yes)
			(effects
				(font
					(size 1 1)
					(thickness 0.15)
				)
				(justify mirror)
			)
		)
		(property "Voltage" "6V"
			(at 0 0 270)
			(unlocked yes)
			(layer "B.Fab")
			(hide yes)
			(effects
				(font
					(size 1 1)
					(thickness 0.15)
				)
				(justify mirror)
			)
		)
		(property "Dielectric" "template_dielectric"
			(at 0 0 270)
			(unlocked yes)
			(layer "B.Fab")
			(hide yes)
			(effects
				(font
					(size 1 1)
					(thickness 0.15)
				)
				(justify mirror)
			)
		)
		(sheetname "/X710-AT2 power/")
		(sheetfile "x710-at2-power.kicad_sch")
		(attr smd)
		(fp_line
			(start -1.95 1.25)
			(end -1.95 0.95)
			(stroke
				(width 0.12)
				(type solid)
			)
			(layer "B.SilkS")
		)
		(fp_line
			(start -2.1 1.1)
			(end -1.8 1.1)
			(stroke
				(width 0.12)
				(type solid)
			)
			(layer "B.SilkS")
		)
		(fp_line
			(start -1.5 0.85)
			(end 1.5 0.85)
			(stroke
				(width 0.12)
				(type solid)
			)
			(layer "B.SilkS")
		)
		(fp_line
			(start -1.5 0.75)
			(end -1.5 0.85)
			(stroke
				(width 0.12)
				(type solid)
			)
			(layer "B.SilkS")
		)
		(fp_line
			(start 1.5 0.75)
			(end 1.5 0.85)
			(stroke
				(width 0.12)
				(type solid)
			)
			(layer "B.SilkS")
		)
		(fp_line
			(start -1.5 -0.75)
			(end -1.5 -0.85)
			(stroke
				(width 0.12)
				(type solid)
			)
			(layer "B.SilkS")
		)
		(fp_line
			(start 1.5 -0.75)
			(end 1.5 -0.85)
			(stroke
				(width 0.12)
				(type solid)
			)
			(layer "B.SilkS")
		)
		(fp_line
			(start 1.5 -0.85)
			(end -1.5 -0.85)
			(stroke
				(width 0.12)
				(type solid)
			)
			(layer "B.SilkS")
		)
		(fp_line
			(start 1.7 1.05)
			(end -1.7 1.05)
			(stroke
				(width 0.05)
				(type solid)
			)
			(layer "B.CrtYd")
		)
		(fp_line
			(start -2.05 0.85)
			(end -2.05 -0.85)
			(stroke
				(width 0.05)
				(type solid)
			)
			(layer "B.CrtYd")
		)
		(fp_line
			(start -1.7 0.85)
			(end -1.7 1.05)
			(stroke
				(width 0.05)
				(type solid)
			)
			(layer "B.CrtYd")
		)
		(fp_line
			(start -1.7 0.85)
			(end -2.05 0.85)
			(stroke
				(width 0.05)
				(type solid)
			)
			(layer "B.CrtYd")
		)
		(fp_line
			(start 1.7 0.85)
			(end 1.7 1.05)
			(stroke
				(width 0.05)
				(type solid)
			)
			(layer "B.CrtYd")
		)
		(fp_line
			(start 2.05 0.85)
			(end 1.7 0.85)
			(stroke
				(width 0.05)
				(type solid)
			)
			(layer "B.CrtYd")
		)
		(fp_line
			(start 2.05 0.85)
			(end 2.05 -0.85)
			(stroke
				(width 0.05)
				(type solid)
			)
			(layer "B.CrtYd")
		)
		(fp_line
			(start -1.7 -0.85)
			(end -2.05 -0.85)
			(stroke
				(width 0.05)
				(type solid)
			)
			(layer "B.CrtYd")
		)
		(fp_line
			(start 2.05 -0.85)
			(end 1.7 -0.85)
			(stroke
				(width 0.05)
				(type solid)
			)
			(layer "B.CrtYd")
		)
		(fp_line
			(start -1.7 -1.05)
			(end -1.7 -0.85)
			(stroke
				(width 0.05)
				(type solid)
			)
			(layer "B.CrtYd")
		)
		(fp_line
			(start 1.7 -1.05)
			(end 1.7 -0.85)
			(stroke
				(width 0.05)
				(type solid)
			)
			(layer "B.CrtYd")
		)
		(fp_line
			(start 1.7 -1.05)
			(end -1.7 -1.05)
			(stroke
				(width 0.05)
				(type solid)
			)
			(layer "B.CrtYd")
		)
		(fp_rect
			(start -1.601 0.802)
			(end 1.6 -0.8)
			(stroke
				(width 0.1)
				(type solid)
			)
			(fill no)
			(layer "B.Fab")
		)
		(fp_text user "License: Apache-2.0"
			(at -2.1 -5.198 90)
			(layer "B.Fab")
			(effects
				(font
					(size 0.7 0.7)
					(thickness 0.15)
				)
				(justify left bottom mirror)
			)
		)
		(fp_text user "${REFERENCE}"
			(at -2.1 -4.198 90)
			(layer "B.Fab")
			(effects
				(font
					(size 0.7 0.7)
					(thickness 0.15)
				)
				(justify left bottom mirror)
			)
		)
		(fp_text user "Author: Antmicro"
			(at -2.1 -6.198 90)
			(layer "B.Fab")
			(effects
				(font
					(size 0.7 0.7)
					(thickness 0.15)
				)
				(justify left bottom mirror)
			)
		)
		(pad "1" smd roundrect
			(at -1.2 0 270)
			(size 1.2 1.2)
			(layers "B.Cu" "B.Mask" "B.Paste")
			(roundrect_rratio 0.1)
			(net 6 "DVDD")
			(pintype "passive")
		)
		(pad "2" smd roundrect
			(at 1.2 0 270)
			(size 1.2 1.2)
			(layers "B.Cu" "B.Mask" "B.Paste")
			(roundrect_rratio 0.1)
			(net 23 "GND")
			(pintype "passive")
		)
	)
	(footprint "antmicro-footprints:R_0402_1005Metric"
		(layer "B.Cu")
		(at 149.331865 82.260117)
		(descr "Resistor SMD 0402")
		(tags "resistor SMD 0402")
		(property "Reference" "R126"
			(at 19.468135 9.464883 180)
			(layer "B.SilkS")
			(effects
				(font
					(size 0.7 0.7)
					(thickness 0.15)
				)
				(justify mirror)
			)
		)
		(property "Value" "R_100R_0402"
			(at -1.011843 -1.772047 180)
			(layer "B.Fab")
			(effects
				(font
					(size 0.7 0.7)
					(thickness 0.15)
				)
				(justify left bottom mirror)
			)
		)
		(property "Datasheet" "https://www.bourns.com/docs/product-datasheets/cr.pdf"
			(at 0 0 180)
			(layer "B.Fab")
			(hide yes)
			(effects
				(font
					(size 1.27 1.27)
					(thickness 0.15)
				)
				(justify mirror)
			)
		)
		(property "Description" "SMD Chip Resistor, 100 ohm, ± 1%, 62.5 mW, 0402 [1005 Metric], Thick Film, General Purpose"
			(at 0 0 180)
			(layer "B.Fab")
			(hide yes)
			(effects
				(font
					(size 1.27 1.27)
					(thickness 0.15)
				)
				(justify mirror)
			)
		)
		(property "MPN" "CR0402-FX-1000GLF"
			(at 0 0 0)
			(unlocked yes)
			(layer "B.Fab")
			(hide yes)
			(effects
				(font
					(size 1 1)
					(thickness 0.15)
				)
				(justify mirror)
			)
		)
		(property "Manufacturer" "Bourns"
			(at 0 0 0)
			(unlocked yes)
			(layer "B.Fab")
			(hide yes)
			(effects
				(font
					(size 1 1)
					(thickness 0.15)
				)
				(justify mirror)
			)
		)
		(property "License" "Apache-2.0"
			(at 0 0 0)
			(unlocked yes)
			(layer "B.Fab")
			(hide yes)
			(effects
				(font
					(size 1 1)
					(thickness 0.15)
				)
				(justify mirror)
			)
		)
		(property "Author" "Antmicro"
			(at 0 0 0)
			(unlocked yes)
			(layer "B.Fab")
			(hide yes)
			(effects
				(font
					(size 1 1)
					(thickness 0.15)
				)
				(justify mirror)
			)
		)
		(property "Val" "100R"
			(at 0 0 0)
			(unlocked yes)
			(layer "B.Fab")
			(hide yes)
			(effects
				(font
					(size 1 1)
					(thickness 0.15)
				)
				(justify mirror)
			)
		)
		(property "Tolerance" "1%"
			(at 0 0 0)
			(unlocked yes)
			(layer "B.Fab")
			(hide yes)
			(effects
				(font
					(size 1 1)
					(thickness 0.15)
				)
				(justify mirror)
			)
		)
		(sheetname "/X710-AT2 RSVD/")
		(sheetfile "x710-at2-rsvd.kicad_sch")
		(attr smd)
		(fp_rect
			(start -0.925 0.47)
			(end 0.925 -0.47)
			(stroke
				(width 0.05)
				(type default)
			)
			(fill no)
			(layer "B.CrtYd")
		)
		(fp_rect
			(start -0.5 0.25)
			(end 0.5 -0.25)
			(stroke
				(width 0.15)
				(type solid)
			)
			(fill no)
			(layer "B.Fab")
		)
		(fp_text user "Author: Antmicro"
			(at -0.95 -4.169 180)
			(layer "B.Fab")
			(effects
				(font
					(size 0.7 0.7)
					(thickness 0.15)
				)
				(justify left bottom mirror)
			)
		)
		(fp_text user "License: Apache-2.0"
			(at -0.95 -5.169 180)
			(layer "B.Fab")
			(effects
				(font
					(size 0.7 0.7)
					(thickness 0.15)
				)
				(justify left bottom mirror)
			)
		)
		(fp_text user "${REFERENCE}"
			(at -0.95 -3.168 180)
			(layer "B.Fab")
			(effects
				(font
					(size 0.7 0.7)
					(thickness 0.15)
				)
				(justify left bottom mirror)
			)
		)
		(pad "1" smd roundrect
			(at -0.48 0)
			(size 0.59 0.64)
			(layers "B.Cu" "B.Mask" "B.Paste")
			(roundrect_rratio 0.25)
			(net 23 "GND")
			(pintype "passive")
		)
		(pad "2" smd roundrect
			(at 0.48 0)
			(size 0.59 0.64)
			(layers "B.Cu" "B.Mask" "B.Paste")
			(roundrect_rratio 0.25)
			(net 97 "/X710-AT2 RSVD/RSVDP22_VSS")
			(pintype "passive")
		)
	)
	(footprint "antmicro-footprints:C_0402_1005Metric"
		(layer "B.Cu")
		(at 129.474999 123.950001 -90)
		(descr "Capacitor SMD 0402")
		(tags "capacitor SMD 0402")
		(property "Reference" "C76"
			(at -7.700002 -21.900002 90)
			(layer "B.SilkS")
			(effects
				(font
					(size 0.7 0.7)
					(thickness 0.15)
				)
				(justify mirror)
			)
		)
		(property "Value" "C_1u_0402"
			(at -1.022927 -2.155213 90)
			(layer "B.Fab")
			(effects
				(font
					(size 0.7 0.7)
					(thickness 0.15)
				)
				(justify left bottom mirror)
			)
		)
		(property "Datasheet" "https://product.tdk.com/en/search/capacitor/ceramic/mlcc/info?part_no=C1005X6S1A105K050BC"
			(at 0 0 90)
			(layer "B.Fab")
			(hide yes)
			(effects
				(font
					(size 1.27 1.27)
					(thickness 0.15)
				)
				(justify mirror)
			)
		)
		(property "Description" "SMD Multilayer Ceramic Capacitor, 1 µF, 10 V, 0402 [1005 Metric], ± 10%, X6S, C"
			(at 0 0 90)
			(layer "B.Fab")
			(hide yes)
			(effects
				(font
					(size 1.27 1.27)
					(thickness 0.15)
				)
				(justify mirror)
			)
		)
		(property "MPN" "C1005X6S1A105K050BC"
			(at 0 0 270)
			(unlocked yes)
			(layer "B.Fab")
			(hide yes)
			(effects
				(font
					(size 1 1)
					(thickness 0.15)
				)
				(justify mirror)
			)
		)
		(property "Manufacturer" "TDK"
			(at 0 0 270)
			(unlocked yes)
			(layer "B.Fab")
			(hide yes)
			(effects
				(font
					(size 1 1)
					(thickness 0.15)
				)
				(justify mirror)
			)
		)
		(property "License" "Apache-2.0"
			(at 0 0 270)
			(unlocked yes)
			(layer "B.Fab")
			(hide yes)
			(effects
				(font
					(size 1 1)
					(thickness 0.15)
				)
				(justify mirror)
			)
		)
		(property "Val" "1u"
			(at 0 0 270)
			(unlocked yes)
			(layer "B.Fab")
			(hide yes)
			(effects
				(font
					(size 1 1)
					(thickness 0.15)
				)
				(justify mirror)
			)
		)
		(property "Voltage" ""
			(at 0 0 270)
			(unlocked yes)
			(layer "B.Fab")
			(hide yes)
			(effects
				(font
					(size 1 1)
					(thickness 0.15)
				)
				(justify mirror)
			)
		)
		(property "Dielectric" ""
			(at 0 0 270)
			(unlocked yes)
			(layer "B.Fab")
			(hide yes)
			(effects
				(font
					(size 1 1)
					(thickness 0.15)
				)
				(justify mirror)
			)
		)
		(property "Author" "Antmicro"
			(at 0 0 270)
			(unlocked yes)
			(layer "B.Fab")
			(hide yes)
			(effects
				(font
					(size 1 1)
					(thickness 0.15)
				)
				(justify mirror)
			)
		)
		(sheetname "/TB Controller - Power/")
		(sheetfile "tb-power.kicad_sch")
		(attr smd)
		(fp_rect
			(start -0.925 0.47)
			(end 0.925 -0.47)
			(stroke
				(width 0.05)
				(type default)
			)
			(fill no)
			(layer "B.CrtYd")
		)
		(fp_line
			(start -0.494 0.25)
			(end 0.504 0.25)
			(stroke
				(width 0.15)
				(type solid)
			)
			(layer "B.Fab")
		)
		(fp_line
			(start 0.504 0.25)
			(end 0.504 -0.248)
			(stroke
				(width 0.15)
				(type solid)
			)
			(layer "B.Fab")
		)
		(fp_line
			(start -0.494 -0.248)
			(end -0.494 0.25)
			(stroke
				(width 0.15)
				(type solid)
			)
			(layer "B.Fab")
		)
		(fp_line
			(start 0.504 -0.248)
			(end -0.494 -0.248)
			(stroke
				(width 0.15)
				(type solid)
			)
			(layer "B.Fab")
		)
		(fp_text user "Author: Antmicro"
			(at -0.939 -3.399 90)
			(layer "B.Fab")
			(effects
				(font
					(size 0.7 0.7)
					(thickness 0.15)
				)
				(justify left bottom mirror)
			)
		)
		(fp_text user "License: Apache-2.0"
			(at -0.939 -5.799 90)
			(layer "B.Fab")
			(effects
				(font
					(size 0.7 0.7)
					(thickness 0.15)
				)
				(justify left bottom mirror)
			)
		)
		(fp_text user "${REFERENCE}"
			(at -0.939 -4.599 90)
			(layer "B.Fab")
			(effects
				(font
					(size 0.7 0.7)
					(thickness 0.15)
				)
				(justify left bottom mirror)
			)
		)
		(pad "1" smd roundrect
			(at -0.48 0 270)
			(size 0.59 0.64)
			(layers "B.Cu" "B.Mask" "B.Paste")
			(roundrect_rratio 0.25)
			(net 23 "GND")
			(pintype "passive")
		)
		(pad "2" smd roundrect
			(at 0.48 0 270)
			(size 0.59 0.64)
			(layers "B.Cu" "B.Mask" "B.Paste")
			(roundrect_rratio 0.25)
			(net 68 "/TB Controller - Power/VCC_0P9")
			(pintype "passive")
		)
	)
	(footprint "antmicro-footprints:C_0402_1005Metric"
		(layer "B.Cu")
		(at 156.111865 88.045116 180)
		(descr "Capacitor SMD 0402")
		(tags "capacitor SMD 0402")
		(property "Reference" "C182"
			(at -19.873134 -9.464883 0)
			(layer "B.SilkS")
			(effects
				(font
					(size 0.7 0.7)
					(thickness 0.15)
				)
				(justify mirror)
			)
		)
		(property "Value" "C_1u_25V_0402"
			(at -1.022927 -2.155213 0)
			(layer "B.Fab")
			(effects
				(font
					(size 0.7 0.7)
					(thickness 0.15)
				)
				(justify left bottom mirror)
			)
		)
		(property "Datasheet" "https://www.murata.com/products/productdetail?partno=GRM155R61E105KE11%23"
			(at 0 0 0)
			(layer "B.Fab")
			(hide yes)
			(effects
				(font
					(size 1.27 1.27)
					(thickness 0.15)
				)
				(justify mirror)
			)
		)
		(property "Description" "SMD Multilayer Ceramic Capacitor, 1 µF, 25 V, 0402 [1005 Metric], ± 10%, X5R, GRM Series"
			(at 0 0 0)
			(layer "B.Fab")
			(hide yes)
			(effects
				(font
					(size 1.27 1.27)
					(thickness 0.15)
				)
				(justify mirror)
			)
		)
		(property "MPN" "GRM155R61E105KE11J"
			(at 0 0 180)
			(unlocked yes)
			(layer "B.Fab")
			(hide yes)
			(effects
				(font
					(size 1 1)
					(thickness 0.15)
				)
				(justify mirror)
			)
		)
		(property "Manufacturer" "Murata"
			(at 0 0 180)
			(unlocked yes)
			(layer "B.Fab")
			(hide yes)
			(effects
				(font
					(size 1 1)
					(thickness 0.15)
				)
				(justify mirror)
			)
		)
		(property "License" "Apache-2.0"
			(at 0 0 180)
			(unlocked yes)
			(layer "B.Fab")
			(hide yes)
			(effects
				(font
					(size 1 1)
					(thickness 0.15)
				)
				(justify mirror)
			)
		)
		(property "Author" "Antmicro"
			(at 0 0 180)
			(unlocked yes)
			(layer "B.Fab")
			(hide yes)
			(effects
				(font
					(size 1 1)
					(thickness 0.15)
				)
				(justify mirror)
			)
		)
		(property "Val" "1u"
			(at 0 0 180)
			(unlocked yes)
			(layer "B.Fab")
			(hide yes)
			(effects
				(font
					(size 1 1)
					(thickness 0.15)
				)
				(justify mirror)
			)
		)
		(property "Voltage" "25V"
			(at 0 0 180)
			(unlocked yes)
			(layer "B.Fab")
			(hide yes)
			(effects
				(font
					(size 1 1)
					(thickness 0.15)
				)
				(justify mirror)
			)
		)
		(property "Dielectric" "X5R"
			(at 0 0 180)
			(unlocked yes)
			(layer "B.Fab")
			(hide yes)
			(effects
				(font
					(size 1 1)
					(thickness 0.15)
				)
				(justify mirror)
			)
		)
		(sheetname "/X710-AT2 power/")
		(sheetfile "x710-at2-power.kicad_sch")
		(attr smd)
		(fp_rect
			(start -0.925 0.47)
			(end 0.925 -0.47)
			(stroke
				(width 0.05)
				(type default)
			)
			(fill no)
			(layer "B.CrtYd")
		)
		(fp_line
			(start 0.504 0.25)
			(end 0.504 -0.248)
			(stroke
				(width 0.15)
				(type solid)
			)
			(layer "B.Fab")
		)
		(fp_line
			(start 0.504 -0.248)
			(end -0.494 -0.248)
			(stroke
				(width 0.15)
				(type solid)
			)
			(layer "B.Fab")
		)
		(fp_line
			(start -0.494 0.25)
			(end 0.504 0.25)
			(stroke
				(width 0.15)
				(type solid)
			)
			(layer "B.Fab")
		)
		(fp_line
			(start -0.494 -0.248)
			(end -0.494 0.25)
			(stroke
				(width 0.15)
				(type solid)
			)
			(layer "B.Fab")
		)
		(fp_text user "${REFERENCE}"
			(at -0.939 -4.599 0)
			(layer "B.Fab")
			(effects
				(font
					(size 0.7 0.7)
					(thickness 0.15)
				)
				(justify left bottom mirror)
			)
		)
		(fp_text user "License: Apache-2.0"
			(at -0.939 -5.799 0)
			(layer "B.Fab")
			(effects
				(font
					(size 0.7 0.7)
					(thickness 0.15)
				)
				(justify left bottom mirror)
			)
		)
		(fp_text user "Author: Antmicro"
			(at -0.939 -3.399 0)
			(layer "B.Fab")
			(effects
				(font
					(size 0.7 0.7)
					(thickness 0.15)
				)
				(justify left bottom mirror)
			)
		)
		(pad "1" smd roundrect
			(at -0.48 0 180)
			(size 0.59 0.64)
			(layers "B.Cu" "B.Mask" "B.Paste")
			(roundrect_rratio 0.25)
			(net 23 "GND")
			(pintype "passive")
		)
		(pad "2" smd roundrect
			(at 0.48 0 180)
			(size 0.59 0.64)
			(layers "B.Cu" "B.Mask" "B.Paste")
			(roundrect_rratio 0.25)
			(net 6 "DVDD")
			(pintype "passive")
		)
	)
)
